(kicad_pcb
	(version 20260206)
	(generator "pcbnew")
	(generator_version "10.0")
	(general
		(thickness 1.6)
		(legacy_teardrops no)
	)
	(paper "A4")
	(title_block
		(title "Wiwynn_Tioga_Pass_MB.brd")
		(comment 1 "Tioga Pass / footprints 1900-1906 of 4770")
	)
	(layers
		(0 "F.Cu" signal "TOP")
		(4 "In1.Cu" signal "L2GND")
		(6 "In2.Cu" signal "L3")
		(8 "In3.Cu" signal "L4GND")
		(10 "In4.Cu" signal "L5")
		(12 "In5.Cu" signal "L6GND")
		(14 "In6.Cu" signal "L7VCC")
		(16 "In7.Cu" signal "L8VCC")
		(18 "In8.Cu" signal "L9GND")
		(20 "In9.Cu" signal "L10")
		(22 "In10.Cu" signal "L11GND")
		(24 "In11.Cu" signal "L12")
		(26 "In12.Cu" signal "L13GND")
		(2 "B.Cu" signal "BOTTOM")
		(9 "F.Adhes" user "F.Adhesive")
		(11 "B.Adhes" user "B.Adhesive")
		(13 "F.Paste" user "Package Geometry/Pastemask Top")
		(15 "B.Paste" user "Package Geometry/Pastemask Bottom")
		(5 "F.SilkS" user "Ref Des/Silkscreen Top")
		(7 "B.SilkS" user "Ref Des/Silkscreen Bottom")
		(1 "F.Mask" user "Board Geometry/Soldermask Top")
		(3 "B.Mask" user "Board Geometry/Soldermask Bottom")
		(17 "Dwgs.User" user "User.Drawings")
		(19 "Cmts.User" user "User.Comments")
		(21 "Eco1.User" user "User.Eco1")
		(23 "Eco2.User" user "User.Eco2")
		(25 "Edge.Cuts" user "Board Geometry/Outline")
		(27 "Margin" user)
		(31 "F.CrtYd" user "Package Geometry/Place Bound Top")
		(29 "B.CrtYd" user "Package Geometry/Place Bound Bottom")
		(35 "F.Fab" user "Ref Des/Assembly Top")
		(33 "B.Fab" user "Ref Des/Assembly Bottom")
	)
	(footprint ""
		(layer "F.Cu")
		(at 476.2246 -145.8849 -90)
		(property "Reference" "U1L3"
			(at 4.98094 2.76733 90)
			(unlocked yes)
			(layer "F.SilkS")
			(effects
				(font
					(size 0.7874 0.5842)
					(thickness 0.1524)
				)
				(justify left)
			)
		)
		(property "Value" ""
			(at 0 0 270)
			(layer "F.Fab")
			(effects
				(font
					(size 1.27 1.27)
				)
			)
		)
		(duplicate_pad_numbers_are_jumpers no)
		(fp_line
			(start 0.9525 2.4765)
			(end 1.778 2.4765)
			(stroke
				(width 0.1524)
				(type default)
			)
			(layer "F.SilkS")
		)
		(fp_line
			(start 1.778 2.4765)
			(end 1.778 1.5875)
			(stroke
				(width 0.1524)
				(type default)
			)
			(layer "F.SilkS")
		)
		(fp_line
			(start 0.381 0.635)
			(end 0.381 1.27)
			(stroke
				(width 0.1524)
				(type default)
			)
			(layer "F.SilkS")
		)
		(fp_line
			(start 0.9525 -0.5715)
			(end 1.778 -0.5715)
			(stroke
				(width 0.1524)
				(type default)
			)
			(layer "F.SilkS")
		)
		(fp_line
			(start 1.778 -0.5715)
			(end 1.778 0.3175)
			(stroke
				(width 0.1524)
				(type default)
			)
			(layer "F.SilkS")
		)
		(fp_circle
			(center -0.9525 -0.9271)
			(end -0.9525 -1.0541)
			(stroke
				(width 0.254)
				(type default)
			)
			(fill no)
			(layer "F.SilkS")
		)
		(fp_poly
			(pts
				(xy 1.778 2.4765) (xy 0.381 2.4765) (xy 0.381 -0.5715) (xy 1.778 -0.5715)
			)
			(stroke
				(width 0)
				(type default)
			)
			(fill no)
			(layer "F.CrtYd")
		)
		(fp_line
			(start 0.381 2.4765)
			(end 1.778 2.4765)
			(stroke
				(width 0.1)
				(type default)
			)
			(layer "F.Fab")
		)
		(fp_line
			(start 1.778 2.4765)
			(end 1.778 -0.5715)
			(stroke
				(width 0.1)
				(type default)
			)
			(layer "F.Fab")
		)
		(fp_line
			(start 0.381 -0.5715)
			(end 0.381 2.4765)
			(stroke
				(width 0.1)
				(type default)
			)
			(layer "F.Fab")
		)
		(fp_line
			(start 1.778 -0.5715)
			(end 0.381 -0.5715)
			(stroke
				(width 0.1)
				(type default)
			)
			(layer "F.Fab")
		)
		(fp_circle
			(center -0.9525 -0.9271)
			(end -0.9525 -1.0541)
			(stroke
				(width 0.254)
				(type default)
			)
			(fill no)
			(layer "F.Fab")
		)
		(pad "1" smd rect
			(at 0 0 270)
			(size 1.143 0.508)
			(layers "F.Cu" "F.Mask" "F.Paste")
			(net "GND")
		)
		(pad "2" smd rect
			(at 0 1.905 270)
			(size 1.143 0.508)
			(layers "F.Cu" "F.Mask" "F.Paste")
			(net "PWRGD_P3V3_R1")
		)
		(pad "3" smd rect
			(at 2.159 0.9525 270)
			(size 1.143 0.508)
			(layers "F.Cu" "F.Mask" "F.Paste")
			(net "P3V3")
		)
	)
	(footprint ""
		(layer "F.Cu")
		(at 227.071936 11.952478 -90)
		(property "Reference" "T1P6"
			(at 0 0 270)
			(layer "F.SilkS")
			(hide yes)
			(effects
				(font
					(size 1.27 1.27)
				)
			)
		)
		(property "Value" "*"
			(at -3.302 1.12395 270)
			(unlocked yes)
			(layer "F.Fab")
			(hide yes)
			(effects
				(font
					(size 0.889 0.889)
					(thickness 0.1524)
				)
			)
		)
		(property "Device Type" "TPAD-DIFF-4P-GP_DISCRET-GB3-TPA"
			(at -3.302 -0.40005 270)
			(unlocked yes)
			(layer "F.Fab")
			(hide yes)
			(effects
				(font
					(size 0.889 0.889)
					(thickness 0.1524)
				)
			)
		)
		(duplicate_pad_numbers_are_jumpers no)
		(fp_line
			(start -2.286 2.286)
			(end 2.286 2.286)
			(stroke
				(width 0.1524)
				(type default)
			)
			(layer "F.SilkS")
		)
		(fp_line
			(start 2.286 2.286)
			(end 2.286 -2.286)
			(stroke
				(width 0.1524)
				(type default)
			)
			(layer "F.SilkS")
		)
		(fp_line
			(start -2.286 -2.286)
			(end -2.286 2.286)
			(stroke
				(width 0.1524)
				(type default)
			)
			(layer "F.SilkS")
		)
		(fp_line
			(start 2.286 -2.286)
			(end -2.286 -2.286)
			(stroke
				(width 0.1524)
				(type default)
			)
			(layer "F.SilkS")
		)
		(fp_line
			(start -2.413 -2.413)
			(end -2.413 -1.143)
			(stroke
				(width 0.4064)
				(type default)
			)
			(layer "F.SilkS")
		)
		(fp_line
			(start -1.143 -2.413)
			(end -2.413 -2.413)
			(stroke
				(width 0.4064)
				(type default)
			)
			(layer "F.SilkS")
		)
		(fp_rect
			(start -2.54 2.54)
			(end 2.54 -2.54)
			(stroke
				(width 0)
				(type default)
			)
			(fill no)
			(layer "F.CrtYd")
		)
		(fp_rect
			(start -2.54 2.54)
			(end 2.54 -2.54)
			(stroke
				(width 0)
				(type default)
			)
			(fill no)
			(layer "F.Fab")
		)
		(pad "1" thru_hole circle
			(at -1.27 -1.27 270)
			(size 1.524 1.524)
			(drill 0.9144)
			(layers "*.Cu" "*.Mask")
			(remove_unused_layers no)
			(net "L14_85OHM_6INCH_DP")
			(clearance -0.0508)
			(thermal_gap 0.127)
			(padstack
				(mode front_inner_back)
				(layer "Inner"
					(shape circle)
					(size 1.1684 1.1684)
					(clearance 0.127)
				)
				(layer "B.Cu"
					(shape circle)
					(size 1.524 1.524)
					(clearance -0.0508)
				)
			)
		)
		(pad "2" thru_hole circle
			(at 1.27 -1.27 270)
			(size 1.524 1.524)
			(drill 0.9144)
			(layers "*.Cu" "*.Mask")
			(remove_unused_layers no)
			(net "L14_85OHM_6INCH_DN")
			(clearance -0.0508)
			(thermal_gap 0.127)
			(padstack
				(mode front_inner_back)
				(layer "Inner"
					(shape circle)
					(size 1.1684 1.1684)
					(clearance 0.127)
				)
				(layer "B.Cu"
					(shape circle)
					(size 1.524 1.524)
					(clearance -0.0508)
				)
			)
		)
		(pad "GND1" thru_hole rect
			(at -1.27 1.27 270)
			(size 1.524 1.524)
			(drill 0.9144)
			(layers "*.Cu" "*.Mask")
			(remove_unused_layers no)
			(net "GND")
			(clearance -0.0508)
			(thermal_gap 0.127)
			(padstack
				(mode front_inner_back)
				(layer "Inner"
					(shape circle)
					(size 1.1684 1.1684)
					(clearance 0.127)
				)
				(layer "B.Cu"
					(shape rect)
					(size 1.524 1.524)
					(clearance -0.0508)
				)
			)
		)
		(pad "GND2" thru_hole rect
			(at 1.27 1.27 270)
			(size 1.524 1.524)
			(drill 0.9144)
			(layers "*.Cu" "*.Mask")
			(remove_unused_layers no)
			(net "GND")
			(clearance -0.0508)
			(thermal_gap 0.127)
			(padstack
				(mode front_inner_back)
				(layer "Inner"
					(shape circle)
					(size 1.1684 1.1684)
					(clearance 0.127)
				)
				(layer "B.Cu"
					(shape rect)
					(size 1.524 1.524)
					(clearance -0.0508)
				)
			)
		)
	)
	(footprint ""
		(layer "F.Cu")
		(at 474.9927 -40.631364 180)
		(property "Reference" "Y9E1"
			(at 2.77749 0.5842 90)
			(unlocked yes)
			(layer "F.SilkS")
			(effects
				(font
					(size 0.7874 0.5842)
					(thickness 0.1524)
				)
				(justify left)
			)
		)
		(property "Value" ""
			(at 0 0 180)
			(layer "F.Fab")
			(effects
				(font
					(size 1.27 1.27)
				)
			)
		)
		(duplicate_pad_numbers_are_jumpers no)
		(fp_circle
			(center -0.668782 -1.07823)
			(end -0.795782 -1.07823)
			(stroke
				(width 0.254)
				(type default)
			)
			(fill no)
			(layer "F.SilkS")
		)
		(fp_rect
			(start -0.499872 2.70002)
			(end 2.100072 -0.599948)
			(stroke
				(width 0)
				(type default)
			)
			(fill no)
			(layer "F.CrtYd")
		)
		(fp_line
			(start 2.100072 2.70002)
			(end -0.499872 2.70002)
			(stroke
				(width 0.1)
				(type default)
			)
			(layer "F.Fab")
		)
		(fp_line
			(start 2.100072 -0.599948)
			(end 2.100072 2.70002)
			(stroke
				(width 0.1)
				(type default)
			)
			(layer "F.Fab")
		)
		(fp_line
			(start -0.499872 2.70002)
			(end -0.499872 -0.599948)
			(stroke
				(width 0.1)
				(type default)
			)
			(layer "F.Fab")
		)
		(fp_line
			(start -0.499872 -0.599948)
			(end 2.100072 -0.599948)
			(stroke
				(width 0.1)
				(type default)
			)
			(layer "F.Fab")
		)
		(fp_circle
			(center -1.049782 -0.44323)
			(end -1.176782 -0.44323)
			(stroke
				(width 0.254)
				(type default)
			)
			(fill no)
			(layer "F.Fab")
		)
		(pad "1" smd rect
			(at 0 0 180)
			(size 1.0414 1.143)
			(layers "F.Cu" "F.Mask" "F.Paste")
			(net "XTAL_25MHZ_IN")
		)
		(pad "2" smd rect
			(at 0 2.100072 180)
			(size 1.0414 1.143)
			(layers "F.Cu" "F.Mask" "F.Paste")
			(net "GND")
		)
		(pad "3" smd rect
			(at 1.6002 2.100072 180)
			(size 1.0414 1.143)
			(layers "F.Cu" "F.Mask" "F.Paste")
			(net "XTAL_25MHZ_OUT_R")
		)
		(pad "4" smd rect
			(at 1.6002 0 180)
			(size 1.0414 1.143)
			(layers "F.Cu" "F.Mask" "F.Paste")
			(net "GND")
		)
	)
	(footprint ""
		(layer "F.Cu")
		(at 417.8935 -64.897 -90)
		(property "Reference" "R8W1"
			(at -0.8382 -0.67818 270)
			(unlocked yes)
			(layer "F.SilkS")
			(effects
				(font
					(size 0.4064 0.254)
					(thickness 0.1524)
				)
				(justify left)
			)
		)
		(property "Value" ""
			(at 0 0 270)
			(layer "F.Fab")
			(effects
				(font
					(size 1.27 1.27)
				)
			)
		)
		(duplicate_pad_numbers_are_jumpers no)
		(fp_poly
			(pts
				(xy -0.2794 -0.1016) (xy 0.2794 -0.1016) (xy 0.2794 0.9906) (xy -0.2794 0.9906)
			)
			(stroke
				(width 0)
				(type default)
			)
			(fill no)
			(layer "F.CrtYd")
		)
		(fp_line
			(start -0.2794 0.9906)
			(end 0.2794 0.9906)
			(stroke
				(width 0.1)
				(type default)
			)
			(layer "F.Fab")
		)
		(fp_line
			(start 0.2794 0.9906)
			(end 0.2794 -0.1016)
			(stroke
				(width 0.1)
				(type default)
			)
			(layer "F.Fab")
		)
		(fp_line
			(start -0.2794 -0.1016)
			(end -0.2794 0.9906)
			(stroke
				(width 0.1)
				(type default)
			)
			(layer "F.Fab")
		)
		(fp_line
			(start 0.2794 -0.1016)
			(end -0.2794 -0.1016)
			(stroke
				(width 0.1)
				(type default)
			)
			(layer "F.Fab")
		)
		(pad "1" smd rect
			(at 0 0 270)
			(size 0.508 0.508)
			(layers "F.Cu" "F.Mask" "F.Paste")
			(net "BMC_SELF_HW_D_RST")
		)
		(pad "2" smd rect
			(at 0 0.889 270)
			(size 0.508 0.508)
			(layers "F.Cu" "F.Mask" "F.Paste")
			(net "FM_TPM_PRES_RST_N")
		)
		(zone
			(layer "F.Cu")
			(hatch none 0.5)
			(connect_pads
				(clearance 0)
			)
			(min_thickness 0.25)
			(keepout
				(tracks not_allowed)
				(vias allowed)
				(pads allowed)
				(copperpour not_allowed)
				(footprints allowed)
			)
			(placement
				(enabled no)
				(sheetname "")
			)
			(fill
				(thermal_gap 0.5)
				(thermal_bridge_width 0.5)
				(island_removal_mode 0)
			)
			(polygon
				(pts
					(xy 417.2585 -65.151) (xy 417.2585 -64.643) (xy 417.6395 -64.643) (xy 417.6395 -65.151)
				)
			)
		)
		(zone
			(layer "F.Cu")
			(hatch none 0.5)
			(connect_pads
				(clearance 0)
			)
			(min_thickness 0.25)
			(keepout
				(tracks allowed)
				(vias not_allowed)
				(pads allowed)
				(copperpour not_allowed)
				(footprints allowed)
			)
			(placement
				(enabled no)
				(sheetname "")
			)
			(fill
				(thermal_gap 0.5)
				(thermal_bridge_width 0.5)
				(island_removal_mode 0)
			)
			(polygon
				(pts
					(xy 417.6395 -65.151) (xy 417.6395 -64.643) (xy 417.2585 -64.643) (xy 417.2585 -65.151)
				)
			)
		)
	)
	(footprint ""
		(layer "F.Cu")
		(at 269.4432 -79.6036 180)
		(property "Reference" "C5W1"
			(at 0.97536 0.76708 90)
			(unlocked yes)
			(layer "F.SilkS")
			(effects
				(font
					(size 0.4064 0.254)
					(thickness 0.1524)
				)
			)
		)
		(property "Value" ""
			(at 0 0 180)
			(layer "F.Fab")
			(effects
				(font
					(size 1.27 1.27)
				)
			)
		)
		(duplicate_pad_numbers_are_jumpers no)
		(fp_poly
			(pts
				(xy -0.4953 -0.2032) (xy 0.4953 -0.2032) (xy 0.4953 1.6002) (xy -0.4953 1.6002)
			)
			(stroke
				(width 0)
				(type default)
			)
			(fill no)
			(layer "F.CrtYd")
		)
		(fp_line
			(start 0.4953 1.6002)
			(end -0.4953 1.6002)
			(stroke
				(width 0.1)
				(type default)
			)
			(layer "F.Fab")
		)
		(fp_line
			(start 0.4953 -0.2032)
			(end 0.4953 1.6002)
			(stroke
				(width 0.1)
				(type default)
			)
			(layer "F.Fab")
		)
		(fp_line
			(start -0.4953 1.6002)
			(end -0.4953 -0.2032)
			(stroke
				(width 0.1)
				(type default)
			)
			(layer "F.Fab")
		)
		(fp_line
			(start -0.4953 -0.2032)
			(end 0.4953 -0.2032)
			(stroke
				(width 0.1)
				(type default)
			)
			(layer "F.Fab")
		)
		(pad "1" smd rect
			(at 0 0 180)
			(size 0.762 0.889)
			(layers "F.Cu" "F.Mask" "F.Paste")
			(net "PVCCMCP_CPU0")
		)
		(pad "2" smd rect
			(at 0 1.397 180)
			(size 0.762 0.889)
			(layers "F.Cu" "F.Mask" "F.Paste")
			(net "GND")
		)
		(zone
			(layer "F.Cu")
			(hatch none 0.5)
			(connect_pads
				(clearance 0)
			)
			(min_thickness 0.25)
			(keepout
				(tracks not_allowed)
				(vias allowed)
				(pads allowed)
				(copperpour not_allowed)
				(footprints allowed)
			)
			(placement
				(enabled no)
				(sheetname "")
			)
			(fill
				(thermal_gap 0.5)
				(thermal_bridge_width 0.5)
				(island_removal_mode 0)
			)
			(polygon
				(pts
					(xy 269.8242 -80.0481) (xy 269.0622 -80.0481) (xy 269.0622 -80.5561) (xy 269.8242 -80.5561)
				)
			)
		)
	)
	(footprint ""
		(layer "F.Cu")
		(at 28.8036 -58.7883 90)
		(property "Reference" "C1E11"
			(at 0 0 90)
			(layer "F.SilkS")
			(hide yes)
			(effects
				(font
					(size 1.27 1.27)
				)
			)
		)
		(property "Value" ""
			(at 0 0 90)
			(layer "F.Fab")
			(effects
				(font
					(size 1.27 1.27)
				)
			)
		)
		(duplicate_pad_numbers_are_jumpers no)
		(fp_rect
			(start -0.3048 0.9906)
			(end 0.3048 -0.1016)
			(stroke
				(width 0)
				(type default)
			)
			(fill no)
			(layer "F.CrtYd")
		)
		(fp_line
			(start 0.3048 -0.1016)
			(end -0.3048 -0.1016)
			(stroke
				(width 0.1)
				(type default)
			)
			(layer "F.Fab")
		)
		(fp_line
			(start -0.3048 -0.1016)
			(end -0.3048 0.9906)
			(stroke
				(width 0.1)
				(type default)
			)
			(layer "F.Fab")
		)
		(fp_line
			(start 0.3048 0.9906)
			(end 0.3048 -0.1016)
			(stroke
				(width 0.1)
				(type default)
			)
			(layer "F.Fab")
		)
		(fp_line
			(start -0.3048 0.9906)
			(end 0.3048 0.9906)
			(stroke
				(width 0.1)
				(type default)
			)
			(layer "F.Fab")
		)
		(pad "1" smd rect
			(at 0 0 90)
			(size 0.508 0.508)
			(layers "F.Cu" "F.Mask" "F.Paste")
			(net "VR_PVCCIN_CPU1_PH1_BOOT")
		)
		(pad "2" smd rect
			(at 0 0.889 90)
			(size 0.508 0.508)
			(layers "F.Cu" "F.Mask" "F.Paste")
			(net "VR_PVCCIN_CPU1_PH1_PHASE")
		)
		(zone
			(layer "F.Cu")
			(hatch none 0.5)
			(connect_pads
				(clearance 0)
			)
			(min_thickness 0.25)
			(keepout
				(tracks not_allowed)
				(vias allowed)
				(pads allowed)
				(copperpour not_allowed)
				(footprints allowed)
			)
			(placement
				(enabled no)
				(sheetname "")
			)
			(fill
				(thermal_gap 0.5)
				(thermal_bridge_width 0.5)
				(island_removal_mode 0)
			)
			(polygon
				(pts
					(xy 29.4386 -58.5343) (xy 29.4386 -59.0423) (xy 29.0576 -59.0423) (xy 29.0576 -58.5343)
				)
			)
		)
		(zone
			(layer "F.Cu")
			(hatch none 0.5)
			(connect_pads
				(clearance 0)
			)
			(min_thickness 0.25)
			(keepout
				(tracks allowed)
				(vias not_allowed)
				(pads allowed)
				(copperpour not_allowed)
				(footprints allowed)
			)
			(placement
				(enabled no)
				(sheetname "")
			)
			(fill
				(thermal_gap 0.5)
				(thermal_bridge_width 0.5)
				(island_removal_mode 0)
			)
			(polygon
				(pts
					(xy 29.4386 -58.5343) (xy 29.4386 -59.0423) (xy 29.0576 -59.0423) (xy 29.0576 -58.5343)
				)
			)
		)
	)
	(footprint ""
		(layer "F.Cu")
		(at 318.643 -130.3528 -90)
		(property "Reference" "C6B1"
			(at 0 0 270)
			(layer "F.SilkS")
			(hide yes)
			(effects
				(font
					(size 1.27 1.27)
				)
			)
		)
		(property "Value" ""
			(at 0 0 270)
			(layer "F.Fab")
			(effects
				(font
					(size 1.27 1.27)
				)
			)
		)
		(duplicate_pad_numbers_are_jumpers no)
		(fp_poly
			(pts
				(xy -0.4953 -0.2032) (xy 0.4953 -0.2032) (xy 0.4953 1.6002) (xy -0.4953 1.6002)
			)
			(stroke
				(width 0)
				(type default)
			)
			(fill no)
			(layer "F.CrtYd")
		)
		(fp_line
			(start -0.4953 1.6002)
			(end -0.4953 -0.2032)
			(stroke
				(width 0.1)
				(type default)
			)
			(layer "F.Fab")
		)
		(fp_line
			(start 0.4953 1.6002)
			(end -0.4953 1.6002)
			(stroke
				(width 0.1)
				(type default)
			)
			(layer "F.Fab")
		)
		(fp_line
			(start -0.4953 -0.2032)
			(end 0.4953 -0.2032)
			(stroke
				(width 0.1)
				(type default)
			)
			(layer "F.Fab")
		)
		(fp_line
			(start 0.4953 -0.2032)
			(end 0.4953 1.6002)
			(stroke
				(width 0.1)
				(type default)
			)
			(layer "F.Fab")
		)
		(pad "1" smd rect
			(at 0 0 270)
			(size 0.762 0.889)
			(layers "F.Cu" "F.Mask" "F.Paste")
			(net "PVPP_DEF")
		)
		(pad "2" smd rect
			(at 0 1.397 270)
			(size 0.762 0.889)
			(layers "F.Cu" "F.Mask" "F.Paste")
			(net "GND")
		)
		(zone
			(layer "F.Cu")
			(hatch none 0.5)
			(connect_pads
				(clearance 0)
			)
			(min_thickness 0.25)
			(keepout
				(tracks not_allowed)
				(vias allowed)
				(pads allowed)
				(copperpour not_allowed)
				(footprints allowed)
			)
			(placement
				(enabled no)
				(sheetname "")
			)
			(fill
				(thermal_gap 0.5)
				(thermal_bridge_width 0.5)
				(island_removal_mode 0)
			)
			(polygon
				(pts
					(xy 318.1985 -130.7338) (xy 318.1985 -129.9718) (xy 317.6905 -129.9718) (xy 317.6905 -130.7338)
				)
			)
		)
	)
)
